(kicad_pcb
	(version 20260206)
	(generator "pcbnew")
	(generator_version "10.0")
	(general
		(thickness 1.6)
		(legacy_teardrops no)
	)
	(paper "A4")
	(title_block
		(title "panther-plus-userver — 13130-1b_20150205.brd")
		(comment 1 "Honey Badger (Wiwynn) / footprints 672-680 of 1509")
	)
	(layers
		(0 "F.Cu" signal "TOP")
		(4 "In1.Cu" signal "L2")
		(6 "In2.Cu" signal "L3")
		(8 "In3.Cu" signal "L4")
		(10 "In4.Cu" signal "L5")
		(12 "In5.Cu" signal "L6")
		(14 "In6.Cu" signal "L7")
		(16 "In7.Cu" signal "L8")
		(18 "In8.Cu" signal "L9")
		(20 "In9.Cu" signal "L10")
		(22 "In10.Cu" signal "L11")
		(2 "B.Cu" signal "BOTTOM")
		(9 "F.Adhes" user "F.Adhesive")
		(11 "B.Adhes" user "B.Adhesive")
		(13 "F.Paste" user "Package Geometry/Pastemask Top")
		(15 "B.Paste" user "Package Geometry/Pastemask Bottom")
		(5 "F.SilkS" user "Ref Des/Silkscreen Top")
		(7 "B.SilkS" user "Ref Des/Silkscreen Bottom")
		(1 "F.Mask" user "Board Geometry/Soldermask Top")
		(3 "B.Mask" user "Board Geometry/Soldermask Bottom")
		(17 "Dwgs.User" user "User.Drawings")
		(19 "Cmts.User" user "User.Comments")
		(21 "Eco1.User" user "User.Eco1")
		(23 "Eco2.User" user "User.Eco2")
		(25 "Edge.Cuts" user "Board Geometry/Outline")
		(27 "Margin" user)
		(31 "F.CrtYd" user "Package Geometry/Place Bound Top")
		(29 "B.CrtYd" user "Package Geometry/Place Bound Bottom")
		(35 "F.Fab" user "Ref Des/Assembly Top")
		(33 "B.Fab" user "Ref Des/Assembly Bottom")
	)
	(footprint ""
		(layer "F.Cu")
		(at 201.3966 -45.72 90)
		(property "Reference" "PG2"
			(at 0 0 90)
			(layer "F.SilkS")
			(hide yes)
			(effects
				(font
					(size 1.27 1.27)
				)
			)
		)
		(property "Value" "GAP-CLOSE-PWR-4-GP"
			(at -2.4638 -0.5461 90)
			(unlocked yes)
			(layer "F.Fab")
			(hide yes)
			(effects
				(font
					(size 1.016 1.016)
					(thickness 0.1524)
				)
			)
		)
		(property "Device Type" "GAP-CLOSE-PWR-4"
			(at -2.4638 -2.0701 90)
			(unlocked yes)
			(layer "F.Fab")
			(hide yes)
			(effects
				(font
					(size 1.016 1.016)
					(thickness 0.1524)
				)
			)
		)
		(duplicate_pad_numbers_are_jumpers no)
		(fp_rect
			(start -0.2794 0.254)
			(end 0.2794 -0.254)
			(stroke
				(width 0)
				(type default)
			)
			(fill no)
			(layer "F.CrtYd")
		)
		(fp_rect
			(start -0.2794 0.254)
			(end 0.2794 -0.254)
			(stroke
				(width 0)
				(type default)
			)
			(fill no)
			(layer "F.Fab")
		)
		(pad "1" smd rect
			(at -0.0635 0 90)
			(size 0.1778 0.254)
			(layers "F.Cu" "F.Mask" "F.Paste")
			(net "VR_PVDDR_A_VSW")
		)
		(pad "2" smd rect
			(at 0.0635 0 90)
			(size 0.1778 0.254)
			(layers "F.Cu" "F.Mask" "F.Paste")
			(net "VR_PVDDRA_R_IS")
		)
	)
	(footprint ""
		(layer "F.Cu")
		(at 132.842 -58.674 90)
		(property "Reference" "PC140"
			(at 0 0 90)
			(layer "F.SilkS")
			(hide yes)
			(effects
				(font
					(size 1.27 1.27)
				)
			)
		)
		(property "Value" "SC10U6D3V3MX-GP"
			(at 0 -2.8194 90)
			(unlocked yes)
			(layer "F.Fab")
			(hide yes)
			(effects
				(font
					(size 1.016 1.016)
					(thickness 0.1524)
				)
			)
		)
		(property "Device Type" "C603H38"
			(at 0 -4.3434 90)
			(unlocked yes)
			(layer "F.Fab")
			(hide yes)
			(effects
				(font
					(size 1.016 1.016)
					(thickness 0.1524)
				)
			)
		)
		(duplicate_pad_numbers_are_jumpers no)
		(fp_line
			(start -0.4064 0)
			(end 0.4064 0)
			(stroke
				(width 0.2286)
				(type default)
			)
			(layer "F.SilkS")
		)
		(fp_rect
			(start -0.635 1.1811)
			(end 0.635 -1.1811)
			(stroke
				(width 0)
				(type default)
			)
			(fill no)
			(layer "F.CrtYd")
		)
		(fp_rect
			(start -0.635 1.1811)
			(end 0.635 -1.1811)
			(stroke
				(width 0)
				(type default)
			)
			(fill no)
			(layer "F.Fab")
		)
		(pad "1" smd custom
			(at 0 -0.6604 90)
			(size 0.19685 0.19685)
			(layers "F.Cu" "F.Mask" "F.Paste")
			(net "GND")
			(options
				(clearance outline)
				(anchor circle)
			)
			(primitives
				(gr_poly
					(pts
						(arc
							(start 0.508 -0.2921)
							(mid 0.478242 -0.363942)
							(end 0.4064 -0.3937)
						)
						(arc
							(start -0.4064 -0.3937)
							(mid -0.478242 -0.363942)
							(end -0.508 -0.2921)
						)
						(arc
							(start -0.508 0.2921)
							(mid -0.478242 0.363942)
							(end -0.4064 0.3937)
						)
						(arc
							(start 0.4064 0.3937)
							(mid 0.478242 0.363942)
							(end 0.508 0.2921)
						)
					)
					(width 0)
					(fill yes)
				)
			)
		)
		(pad "2" smd custom
			(at 0 0.6604 90)
			(size 0.19685 0.19685)
			(layers "F.Cu" "F.Mask" "F.Paste")
			(net "PV_VDDR")
			(options
				(clearance outline)
				(anchor circle)
			)
			(primitives
				(gr_poly
					(pts
						(arc
							(start 0.508 -0.2921)
							(mid 0.478242 -0.363942)
							(end 0.4064 -0.3937)
						)
						(arc
							(start -0.4064 -0.3937)
							(mid -0.478242 -0.363942)
							(end -0.508 -0.2921)
						)
						(arc
							(start -0.508 0.2921)
							(mid -0.478242 0.363942)
							(end -0.4064 0.3937)
						)
						(arc
							(start 0.4064 0.3937)
							(mid 0.478242 0.363942)
							(end 0.508 0.2921)
						)
					)
					(width 0)
					(fill yes)
				)
			)
		)
	)
	(footprint ""
		(layer "F.Cu")
		(at 18.669 -39.243 90)
		(property "Reference" "PL6"
			(at 0 0 90)
			(layer "F.SilkS")
			(hide yes)
			(effects
				(font
					(size 1.27 1.27)
				)
			)
		)
		(property "Value" "IND-2D2UH-122-GP"
			(at -4.8895 -4.2672 90)
			(unlocked yes)
			(layer "F.Fab")
			(hide yes)
			(effects
				(font
					(size 1.016 1.016)
					(thickness 0.1524)
				)
			)
		)
		(property "Device Type" "L686647H119"
			(at -4.8895 -5.7912 90)
			(unlocked yes)
			(layer "F.Fab")
			(hide yes)
			(effects
				(font
					(size 1.016 1.016)
					(thickness 0.1524)
				)
			)
		)
		(duplicate_pad_numbers_are_jumpers no)
		(fp_rect
			(start -3.4925 3.937)
			(end 3.4925 -3.937)
			(stroke
				(width 0)
				(type default)
			)
			(fill no)
			(layer "F.CrtYd")
		)
		(fp_rect
			(start -3.4925 3.937)
			(end 3.4925 -3.937)
			(stroke
				(width 0)
				(type default)
			)
			(fill no)
			(layer "F.Fab")
		)
		(pad "1" smd rect
			(at 0 -2.858516 90)
			(size 3.429 1.905)
			(layers "F.Cu" "F.Mask" "F.Paste")
			(net "P3V3_STBY_LL")
		)
		(pad "2" smd rect
			(at 0 2.858516 90)
			(size 3.429 1.905)
			(layers "F.Cu" "F.Mask" "F.Paste")
			(net "P3V3_STBY_OUT")
		)
	)
	(footprint ""
		(layer "F.Cu")
		(at 77.2922 -35.9156 180)
		(property "Reference" "TP7"
			(at 0 0 180)
			(layer "F.SilkS")
			(hide yes)
			(effects
				(font
					(size 1.27 1.27)
				)
			)
		)
		(property "Value" "TPAD28-1-GP-U"
			(at 0.0508 -1.9304 180)
			(unlocked yes)
			(layer "F.Fab")
			(hide yes)
			(effects
				(font
					(size 1.016 1.016)
					(thickness 0.1524)
				)
			)
		)
		(property "Device Type" "TPAD28-1-U"
			(at 0.0508 -3.4544 180)
			(unlocked yes)
			(layer "F.Fab")
			(hide yes)
			(effects
				(font
					(size 1.016 1.016)
					(thickness 0.1524)
				)
			)
		)
		(duplicate_pad_numbers_are_jumpers no)
		(fp_poly
			(pts
				(arc
					(start -0.3556 0)
					(mid 0.3556 0)
					(end -0.3556 0)
				)
			)
			(stroke
				(width 0)
				(type default)
			)
			(fill no)
			(layer "F.CrtYd")
		)
		(fp_poly
			(pts
				(arc
					(start -0.9525 0)
					(mid 0.9525 0)
					(end -0.9525 0)
				)
			)
			(stroke
				(width 0)
				(type default)
			)
			(fill no)
			(layer "F.Fab")
		)
		(pad "1" smd circle
			(at 0 0 180)
			(size 0.7112 0.7112)
			(layers "F.Cu" "F.Mask" "F.Paste")
			(net "SUS_STAT#")
		)
	)
	(footprint ""
		(layer "F.Cu")
		(at 107.823 -66.167 -90)
		(property "Reference" "C7"
			(at 0 0 270)
			(layer "F.SilkS")
			(hide yes)
			(effects
				(font
					(size 1.27 1.27)
				)
			)
		)
		(property "Value" "SCD1U10V2KX-5GP"
			(at 1.1811 -2.7051 270)
			(unlocked yes)
			(layer "F.Fab")
			(hide yes)
			(effects
				(font
					(size 1.016 1.016)
					(thickness 0.1524)
				)
			)
		)
		(property "Device Type" "C402H22"
			(at 1.1811 -4.2291 270)
			(unlocked yes)
			(layer "F.Fab")
			(hide yes)
			(effects
				(font
					(size 1.016 1.016)
					(thickness 0.1524)
				)
			)
		)
		(duplicate_pad_numbers_are_jumpers no)
		(fp_rect
			(start -0.381 0.7366)
			(end 0.381 -0.7366)
			(stroke
				(width 0)
				(type default)
			)
			(fill no)
			(layer "F.CrtYd")
		)
		(fp_rect
			(start -0.381 0.7366)
			(end 0.381 -0.7366)
			(stroke
				(width 0)
				(type default)
			)
			(fill no)
			(layer "F.Fab")
		)
		(pad "1" smd custom
			(at 0 -0.4572 270)
			(size 0.1143 0.1143)
			(layers "F.Cu" "F.Mask" "F.Paste")
			(net "M_DRAM_PWROK")
			(options
				(clearance outline)
				(anchor circle)
			)
			(primitives
				(gr_poly
					(pts
						(arc
							(start -0.254 -0.1778)
							(mid -0.239121 -0.213721)
							(end -0.2032 -0.2286)
						)
						(arc
							(start 0.2032 -0.2286)
							(mid 0.239121 -0.213721)
							(end 0.254 -0.1778)
						)
						(arc
							(start 0.254 0.1778)
							(mid 0.239121 0.213721)
							(end 0.2032 0.2286)
						)
						(arc
							(start -0.2032 0.2286)
							(mid -0.239121 0.213721)
							(end -0.254 0.1778)
						)
					)
					(width 0)
					(fill yes)
				)
			)
		)
		(pad "2" smd custom
			(at 0 0.4572 270)
			(size 0.1143 0.1143)
			(layers "F.Cu" "F.Mask" "F.Paste")
			(net "GND")
			(options
				(clearance outline)
				(anchor circle)
			)
			(primitives
				(gr_poly
					(pts
						(arc
							(start -0.254 -0.1778)
							(mid -0.239121 -0.213721)
							(end -0.2032 -0.2286)
						)
						(arc
							(start 0.2032 -0.2286)
							(mid 0.239121 -0.213721)
							(end 0.254 -0.1778)
						)
						(arc
							(start 0.254 0.1778)
							(mid 0.239121 0.213721)
							(end 0.2032 0.2286)
						)
						(arc
							(start -0.2032 0.2286)
							(mid -0.239121 0.213721)
							(end -0.254 0.1778)
						)
					)
					(width 0)
					(fill yes)
				)
			)
		)
	)
	(footprint ""
		(layer "F.Cu")
		(at 66.802 -45.72 -90)
		(property "Reference" "U9"
			(at 0 0 270)
			(layer "F.SilkS")
			(hide yes)
			(effects
				(font
					(size 1.27 1.27)
				)
			)
		)
		(property "Value" "2N7002DW-7F-GP"
			(at -2.3622 -8.2042 270)
			(unlocked yes)
			(layer "F.Fab")
			(hide yes)
			(effects
				(font
					(size 1.016 1.016)
					(thickness 0.1524)
				)
			)
		)
		(property "Device Type" "SOT-363H44"
			(at -2.3622 -10.1092 270)
			(unlocked yes)
			(layer "F.Fab")
			(hide yes)
			(effects
				(font
					(size 1.016 1.016)
					(thickness 0.1524)
				)
			)
		)
		(duplicate_pad_numbers_are_jumpers no)
		(fp_poly
			(pts
				(xy -0.6731 1.4351) (xy -0.9779 1.7399) (xy -0.381 1.7399) (xy -0.3683 1.7399) (xy -0.381 1.7272)
			)
			(stroke
				(width 0)
				(type default)
			)
			(fill yes)
			(layer "F.SilkS")
		)
		(fp_poly
			(pts
				(xy 1.2573 0.8763) (xy 1.2573 -0.8763) (xy 0.9525 -0.8763) (xy 0.9525 -1.4351) (xy -0.9525 -1.4351)
				(xy -0.9525 -0.8763) (xy -1.2573 -0.8763) (xy -1.2573 0.8763) (xy -0.9525 0.8763) (xy -0.9525 1.4351)
				(xy 0.9525 1.4351) (xy 0.9525 0.8763)
			)
			(stroke
				(width 0)
				(type default)
			)
			(fill no)
			(layer "F.CrtYd")
		)
		(fp_poly
			(pts
				(xy 1.2573 0.8763) (xy 1.2573 -0.8763) (xy 0.9525 -0.8763) (xy 0.9525 -1.4351) (xy -0.9525 -1.4351)
				(xy -0.9525 -0.8763) (xy -1.2573 -0.8763) (xy -1.2573 0.8763) (xy -0.9525 0.8763) (xy -0.9525 1.4351)
				(xy 0.9525 1.4351) (xy 0.9525 0.8763)
			)
			(stroke
				(width 0)
				(type default)
			)
			(fill no)
			(layer "F.Fab")
		)
		(pad "1" smd rect
			(at -0.65024 0.8255 270)
			(size 0.3556 0.9652)
			(layers "F.Cu" "F.Mask" "F.Paste")
			(net "SMBUS_PECI_R_DATA")
		)
		(pad "2" smd rect
			(at 0 0.8255 270)
			(size 0.3556 0.9652)
			(layers "F.Cu" "F.Mask" "F.Paste")
			(net "SMBUS_PECI_SW_EN")
		)
		(pad "3" smd rect
			(at 0.65024 0.8255 270)
			(size 0.3556 0.9652)
			(layers "F.Cu" "F.Mask" "F.Paste")
			(net "SMB_PECI_LV_R_CLK")
		)
		(pad "4" smd rect
			(at 0.65024 -0.8255 270)
			(size 0.3556 0.9652)
			(layers "F.Cu" "F.Mask" "F.Paste")
			(net "SMBUS_PECI_R_CLK")
		)
		(pad "5" smd rect
			(at 0 -0.8255 270)
			(size 0.3556 0.9652)
			(layers "F.Cu" "F.Mask" "F.Paste")
			(net "SMBUS_PECI_SW_EN")
		)
		(pad "6" smd rect
			(at -0.65024 -0.8255 270)
			(size 0.3556 0.9652)
			(layers "F.Cu" "F.Mask" "F.Paste")
			(net "SMB_PECI_LV_R_DATA")
		)
	)
	(footprint ""
		(layer "F.Cu")
		(at 55.626 -46.609 -90)
		(property "Reference" "R41"
			(at 0 0 270)
			(layer "F.SilkS")
			(hide yes)
			(effects
				(font
					(size 1.27 1.27)
				)
			)
		)
		(property "Value" "4K7R2F-GP"
			(at 1.7907 -1.1176 270)
			(unlocked yes)
			(layer "F.Fab")
			(hide yes)
			(effects
				(font
					(size 1.016 1.016)
					(thickness 0.1524)
				)
			)
		)
		(property "Device Type" "R402H16"
			(at 1.7907 -2.6416 270)
			(unlocked yes)
			(layer "F.Fab")
			(hide yes)
			(effects
				(font
					(size 1.016 1.016)
					(thickness 0.1524)
				)
			)
		)
		(duplicate_pad_numbers_are_jumpers no)
		(fp_rect
			(start -0.381 0.8382)
			(end 0.381 -0.8382)
			(stroke
				(width 0)
				(type default)
			)
			(fill no)
			(layer "F.CrtYd")
		)
		(fp_rect
			(start -0.381 0.8382)
			(end 0.381 -0.8382)
			(stroke
				(width 0)
				(type default)
			)
			(fill no)
			(layer "F.Fab")
		)
		(pad "1" smd custom
			(at 0 -0.4318 270)
			(size 0.127 0.127)
			(layers "F.Cu" "F.Mask" "F.Paste")
			(net "P12V")
			(options
				(clearance outline)
				(anchor circle)
			)
			(primitives
				(gr_poly
					(pts
						(arc
							(start -0.2032 -0.2794)
							(mid -0.239121 -0.264521)
							(end -0.254 -0.2286)
						)
						(arc
							(start -0.254 0.2286)
							(mid -0.239121 0.264521)
							(end -0.2032 0.2794)
						)
						(arc
							(start 0.2032 0.2794)
							(mid 0.239121 0.264521)
							(end 0.254 0.2286)
						)
						(arc
							(start 0.254 -0.2286)
							(mid 0.239121 -0.264521)
							(end 0.2032 -0.2794)
						)
					)
					(width 0)
					(fill yes)
				)
			)
		)
		(pad "2" smd custom
			(at 0 0.4318 270)
			(size 0.127 0.127)
			(layers "F.Cu" "F.Mask" "F.Paste")
			(net "SW_P3V3_CPU_LV_G5")
			(options
				(clearance outline)
				(anchor circle)
			)
			(primitives
				(gr_poly
					(pts
						(arc
							(start -0.2032 -0.2794)
							(mid -0.239121 -0.264521)
							(end -0.254 -0.2286)
						)
						(arc
							(start -0.254 0.2286)
							(mid -0.239121 0.264521)
							(end -0.2032 0.2794)
						)
						(arc
							(start 0.2032 0.2794)
							(mid 0.239121 0.264521)
							(end 0.254 0.2286)
						)
						(arc
							(start 0.254 -0.2286)
							(mid 0.239121 -0.264521)
							(end 0.2032 -0.2794)
						)
					)
					(width 0)
					(fill yes)
				)
			)
		)
	)
	(footprint ""
		(layer "F.Cu")
		(at 130.175 -56.388 180)
		(property "Reference" "PC52"
			(at 0 0 180)
			(layer "F.SilkS")
			(hide yes)
			(effects
				(font
					(size 1.27 1.27)
				)
			)
		)
		(property "Value" "SC10U6D3V3MX-GP"
			(at 0 -2.8194 180)
			(unlocked yes)
			(layer "F.Fab")
			(hide yes)
			(effects
				(font
					(size 1.016 1.016)
					(thickness 0.1524)
				)
			)
		)
		(property "Device Type" "C603H38"
			(at 0 -4.3434 180)
			(unlocked yes)
			(layer "F.Fab")
			(hide yes)
			(effects
				(font
					(size 1.016 1.016)
					(thickness 0.1524)
				)
			)
		)
		(duplicate_pad_numbers_are_jumpers no)
		(fp_line
			(start -0.4064 0)
			(end 0.4064 0)
			(stroke
				(width 0.2286)
				(type default)
			)
			(layer "F.SilkS")
		)
		(fp_rect
			(start -0.635 1.1811)
			(end 0.635 -1.1811)
			(stroke
				(width 0)
				(type default)
			)
			(fill no)
			(layer "F.CrtYd")
		)
		(fp_rect
			(start -0.635 1.1811)
			(end 0.635 -1.1811)
			(stroke
				(width 0)
				(type default)
			)
			(fill no)
			(layer "F.Fab")
		)
		(pad "1" smd custom
			(at 0 -0.6604 180)
			(size 0.19685 0.19685)
			(layers "F.Cu" "F.Mask" "F.Paste")
			(net "GND")
			(options
				(clearance outline)
				(anchor circle)
			)
			(primitives
				(gr_poly
					(pts
						(arc
							(start 0.508 -0.2921)
							(mid 0.478242 -0.363942)
							(end 0.4064 -0.3937)
						)
						(arc
							(start -0.4064 -0.3937)
							(mid -0.478242 -0.363942)
							(end -0.508 -0.2921)
						)
						(arc
							(start -0.508 0.2921)
							(mid -0.478242 0.363942)
							(end -0.4064 0.3937)
						)
						(arc
							(start 0.4064 0.3937)
							(mid 0.478242 0.363942)
							(end 0.508 0.2921)
						)
					)
					(width 0)
					(fill yes)
				)
			)
		)
		(pad "2" smd custom
			(at 0 0.6604 180)
			(size 0.19685 0.19685)
			(layers "F.Cu" "F.Mask" "F.Paste")
			(net "PV_VTT_DDR_A")
			(options
				(clearance outline)
				(anchor circle)
			)
			(primitives
				(gr_poly
					(pts
						(arc
							(start 0.508 -0.2921)
							(mid 0.478242 -0.363942)
							(end 0.4064 -0.3937)
						)
						(arc
							(start -0.4064 -0.3937)
							(mid -0.478242 -0.363942)
							(end -0.508 -0.2921)
						)
						(arc
							(start -0.508 0.2921)
							(mid -0.478242 0.363942)
							(end -0.4064 0.3937)
						)
						(arc
							(start 0.4064 0.3937)
							(mid 0.478242 0.363942)
							(end 0.508 0.2921)
						)
					)
					(width 0)
					(fill yes)
				)
			)
		)
	)
	(footprint ""
		(layer "F.Cu")
		(at 24.7142 -52.6034 90)
		(property "Reference" "PR69"
			(at 0 0 90)
			(layer "F.SilkS")
			(hide yes)
			(effects
				(font
					(size 1.27 1.27)
				)
			)
		)
		(property "Value" "140R2F-GP"
			(at 1.7907 -1.1176 90)
			(unlocked yes)
			(layer "F.Fab")
			(hide yes)
			(effects
				(font
					(size 1.016 1.016)
					(thickness 0.1524)
				)
			)
		)
		(property "Device Type" "R402H16"
			(at 1.7907 -2.6416 90)
			(unlocked yes)
			(layer "F.Fab")
			(hide yes)
			(effects
				(font
					(size 1.016 1.016)
					(thickness 0.1524)
				)
			)
		)
		(duplicate_pad_numbers_are_jumpers no)
		(fp_rect
			(start -0.381 0.8382)
			(end 0.381 -0.8382)
			(stroke
				(width 0)
				(type default)
			)
			(fill no)
			(layer "F.CrtYd")
		)
		(fp_rect
			(start -0.381 0.8382)
			(end 0.381 -0.8382)
			(stroke
				(width 0)
				(type default)
			)
			(fill no)
			(layer "F.Fab")
		)
		(pad "1" smd custom
			(at 0 -0.4318 90)
			(size 0.127 0.127)
			(layers "F.Cu" "F.Mask" "F.Paste")
			(net "VR_PVCCP_ISUMN_R")
			(options
				(clearance outline)
				(anchor circle)
			)
			(primitives
				(gr_poly
					(pts
						(arc
							(start -0.2032 -0.2794)
							(mid -0.239121 -0.264521)
							(end -0.254 -0.2286)
						)
						(arc
							(start -0.254 0.2286)
							(mid -0.239121 0.264521)
							(end -0.2032 0.2794)
						)
						(arc
							(start 0.2032 0.2794)
							(mid 0.239121 0.264521)
							(end 0.254 0.2286)
						)
						(arc
							(start 0.254 -0.2286)
							(mid 0.239121 -0.264521)
							(end 0.2032 -0.2794)
						)
					)
					(width 0)
					(fill yes)
				)
			)
		)
		(pad "2" smd custom
			(at 0 0.4318 90)
			(size 0.127 0.127)
			(layers "F.Cu" "F.Mask" "F.Paste")
			(net "VR_PVCCP_ISUMN_RC")
			(options
				(clearance outline)
				(anchor circle)
			)
			(primitives
				(gr_poly
					(pts
						(arc
							(start -0.2032 -0.2794)
							(mid -0.239121 -0.264521)
							(end -0.254 -0.2286)
						)
						(arc
							(start -0.254 0.2286)
							(mid -0.239121 0.264521)
							(end -0.2032 0.2794)
						)
						(arc
							(start 0.2032 0.2794)
							(mid 0.239121 0.264521)
							(end 0.254 0.2286)
						)
						(arc
							(start 0.254 -0.2286)
							(mid 0.239121 -0.264521)
							(end 0.2032 -0.2794)
						)
					)
					(width 0)
					(fill yes)
				)
			)
		)
	)
)
